(kicad_pcb
	(version 20260206)
	(generator "pcbnew")
	(generator_version "10.0")
	(general
		(thickness 1.6)
		(legacy_teardrops no)
	)
	(paper "A4")
	(title_block
		(title "baseboard — 13948-1b.1110WZS1818.brd")
		(comment 1 "Honey Badger (Wiwynn) / footprint 852 of 2523 (SU2), pads 855-896 of 896")
	)
	(layers
		(0 "F.Cu" signal "TOP")
		(4 "In1.Cu" signal "L2GND")
		(6 "In2.Cu" signal "L3")
		(8 "In3.Cu" signal "L4VCC")
		(10 "In4.Cu" signal "L5VCC")
		(12 "In5.Cu" signal "L6")
		(14 "In6.Cu" signal "L7GND")
		(2 "B.Cu" signal "BOTTOM")
		(9 "F.Adhes" user "F.Adhesive")
		(11 "B.Adhes" user "B.Adhesive")
		(13 "F.Paste" user "Package Geometry/Pastemask Top")
		(15 "B.Paste" user "Package Geometry/Pastemask Bottom")
		(5 "F.SilkS" user "Ref Des/Silkscreen Top")
		(7 "B.SilkS" user "Ref Des/Silkscreen Bottom")
		(1 "F.Mask" user "Board Geometry/Soldermask Top")
		(3 "B.Mask" user "Board Geometry/Soldermask Bottom")
		(17 "Dwgs.User" user "User.Drawings")
		(19 "Cmts.User" user "User.Comments")
		(21 "Eco1.User" user "User.Eco1")
		(23 "Eco2.User" user "User.Eco2")
		(25 "Edge.Cuts" user "Board Geometry/Outline")
		(27 "Margin" user)
		(31 "F.CrtYd" user "Package Geometry/Place Bound Top")
		(29 "B.CrtYd" user "Package Geometry/Place Bound Bottom")
		(35 "F.Fab" user "Ref Des/Assembly Top")
		(33 "B.Fab" user "Ref Des/Assembly Bottom")
	)
	(footprint ""
		(layer "F.Cu")
		(at 102.350062 -44.99991)
		(property "Reference" "SU2"
			(at 0 0 0)
			(layer "F.SilkS")
			(hide yes)
			(effects
				(font
					(size 1.27 1.27)
				)
			)
		)
		(property "Value" "SAS3008C0-1-DB-500020657-1-GP"
			(at -20.374102 -5.0292 0)
			(unlocked yes)
			(layer "F.Fab")
			(hide yes)
			(effects
				(font
					(size 1.016 1.016)
					(thickness 0.1524)
				)
			)
		)
		(property "Device Type" "BGA896D25H78"
			(at -20.374102 -6.5532 0)
			(unlocked yes)
			(layer "F.Fab")
			(hide yes)
			(effects
				(font
					(size 1.016 1.016)
					(thickness 0.1524)
				)
			)
		)
		(duplicate_pad_numbers_are_jumpers no)
		(pad "W19" smd circle
			(at 2.800096 2.800096)
			(size 0.3556 0.3556)
			(layers "F.Cu" "F.Mask" "F.Paste")
			(net "GND")
		)
		(pad "W20" smd circle
			(at 3.599942 2.800096)
			(size 0.3556 0.3556)
			(layers "F.Cu" "F.Mask" "F.Paste")
			(net "P0V955_C")
		)
		(pad "W21" smd circle
			(at 4.400042 2.800096)
			(size 0.3556 0.3556)
			(layers "F.Cu" "F.Mask" "F.Paste")
			(net "GND")
		)
		(pad "W22" smd circle
			(at 5.199888 2.800096)
			(size 0.3556 0.3556)
			(layers "F.Cu" "F.Mask" "F.Paste")
			(net "GND")
		)
		(pad "W23" smd circle
			(at 5.999988 2.800096)
			(size 0.3556 0.3556)
			(layers "F.Cu" "F.Mask" "F.Paste")
			(net "GND")
		)
		(pad "W24" smd circle
			(at 6.800088 2.800096)
			(size 0.3556 0.3556)
			(layers "F.Cu" "F.Mask" "F.Paste")
			(net "GND")
		)
		(pad "W25" smd circle
			(at 7.599934 2.800096)
			(size 0.3556 0.3556)
			(layers "F.Cu" "F.Mask" "F.Paste")
			(net "GND")
		)
		(pad "W26" smd circle
			(at 8.400034 2.800096)
			(size 0.3556 0.3556)
			(layers "F.Cu" "F.Mask" "F.Paste")
			(net "GND")
		)
		(pad "W27" smd circle
			(at 9.19988 2.800096)
			(size 0.3556 0.3556)
			(layers "F.Cu" "F.Mask" "F.Paste")
			(net "P1V8_C")
		)
		(pad "W28" smd circle
			(at 9.99998 2.800096)
			(size 0.3556 0.3556)
			(layers "F.Cu" "F.Mask" "F.Paste")
			(net "IOC_GPIO_38")
		)
		(pad "W29" smd circle
			(at 10.80008 2.800096)
			(size 0.3556 0.3556)
			(layers "F.Cu" "F.Mask" "F.Paste")
			(net "IOC_SCL_4")
		)
		(pad "W30" smd circle
			(at 11.599926 2.800096)
			(size 0.3556 0.3556)
			(layers "F.Cu" "F.Mask" "F.Paste")
			(net "IOC_GPIO_24")
		)
		(pad "Y1" smd circle
			(at -11.599926 3.599942)
			(size 0.3556 0.3556)
			(layers "F.Cu" "F.Mask" "F.Paste")
			(net "SAS0_VDDH")
		)
		(pad "Y2" smd circle
			(at -10.80008 3.599942)
			(size 0.3556 0.3556)
			(layers "F.Cu" "F.Mask" "F.Paste")
			(net "GND")
		)
		(pad "Y3" smd circle
			(at -9.99998 3.599942)
			(size 0.3556 0.3556)
			(layers "F.Cu" "F.Mask" "F.Paste")
			(net "GND")
		)
		(pad "Y4" smd circle
			(at -9.19988 3.599942)
			(size 0.3556 0.3556)
			(layers "F.Cu" "F.Mask" "F.Paste")
			(net "SAS0_AVDD")
		)
		(pad "Y5" smd circle
			(at -8.400034 3.599942)
			(size 0.3556 0.3556)
			(layers "F.Cu" "F.Mask" "F.Paste")
			(net "GND")
		)
		(pad "Y6" smd circle
			(at -7.599934 3.599942)
			(size 0.3556 0.3556)
			(layers "F.Cu" "F.Mask" "F.Paste")
			(net "SAS0_VDDH")
		)
		(pad "Y7" smd circle
			(at -6.800088 3.599942)
			(size 0.3556 0.3556)
			(layers "F.Cu" "F.Mask" "F.Paste")
			(net "SAS0_AVDD")
		)
		(pad "Y8" smd circle
			(at -5.999988 3.599942)
			(size 0.3556 0.3556)
			(layers "F.Cu" "F.Mask" "F.Paste")
			(net "GND")
		)
		(pad "Y9" smd circle
			(at -5.199888 3.599942)
			(size 0.3556 0.3556)
			(layers "F.Cu" "F.Mask" "F.Paste")
			(net "GND")
		)
		(pad "Y10" smd circle
			(at -4.400042 3.599942)
			(size 0.3556 0.3556)
			(layers "F.Cu" "F.Mask" "F.Paste")
			(net "GND")
		)
		(pad "Y11" smd circle
			(at -3.599942 3.599942)
			(size 0.3556 0.3556)
			(layers "F.Cu" "F.Mask" "F.Paste")
			(net "GND")
		)
		(pad "Y12" smd circle
			(at -2.800096 3.599942)
			(size 0.3556 0.3556)
			(layers "F.Cu" "F.Mask" "F.Paste")
			(net "GND")
		)
		(pad "Y13" smd circle
			(at -1.999996 3.599942)
			(size 0.3556 0.3556)
			(layers "F.Cu" "F.Mask" "F.Paste")
			(net "GND")
		)
		(pad "Y14" smd circle
			(at -1.199896 3.599942)
			(size 0.3556 0.3556)
			(layers "F.Cu" "F.Mask" "F.Paste")
			(net "GND")
		)
		(pad "Y15" smd circle
			(at -0.40005 3.599942)
			(size 0.3556 0.3556)
			(layers "F.Cu" "F.Mask" "F.Paste")
			(net "GND")
		)
		(pad "Y16" smd circle
			(at 0.40005 3.599942)
			(size 0.3556 0.3556)
			(layers "F.Cu" "F.Mask" "F.Paste")
			(net "GND")
		)
		(pad "Y17" smd circle
			(at 1.199896 3.599942)
			(size 0.3556 0.3556)
			(layers "F.Cu" "F.Mask" "F.Paste")
			(net "P0V955_C")
		)
		(pad "Y18" smd circle
			(at 1.999996 3.599942)
			(size 0.3556 0.3556)
			(layers "F.Cu" "F.Mask" "F.Paste")
			(net "GND")
		)
		(pad "Y19" smd circle
			(at 2.800096 3.599942)
			(size 0.3556 0.3556)
			(layers "F.Cu" "F.Mask" "F.Paste")
			(net "P0V955_C")
		)
		(pad "Y20" smd circle
			(at 3.599942 3.599942)
			(size 0.3556 0.3556)
			(layers "F.Cu" "F.Mask" "F.Paste")
			(net "GND")
		)
		(pad "Y21" smd circle
			(at 4.400042 3.599942)
			(size 0.3556 0.3556)
			(layers "F.Cu" "F.Mask" "F.Paste")
			(net "P0V955_C")
		)
		(pad "Y22" smd circle
			(at 5.199888 3.599942)
			(size 0.3556 0.3556)
			(layers "F.Cu" "F.Mask" "F.Paste")
			(net "GND")
		)
		(pad "Y23" smd circle
			(at 5.999988 3.599942)
			(size 0.3556 0.3556)
			(layers "F.Cu" "F.Mask" "F.Paste")
			(net "GND")
		)
		(pad "Y24" smd circle
			(at 6.800088 3.599942)
			(size 0.3556 0.3556)
			(layers "F.Cu" "F.Mask" "F.Paste")
			(net "GND")
		)
		(pad "Y25" smd circle
			(at 7.599934 3.599942)
			(size 0.3556 0.3556)
			(layers "F.Cu" "F.Mask" "F.Paste")
			(net "GND")
		)
		(pad "Y26" smd circle
			(at 8.400034 3.599942)
			(size 0.3556 0.3556)
			(layers "F.Cu" "F.Mask" "F.Paste")
			(net "P1V8_C")
		)
		(pad "Y27" smd circle
			(at 9.19988 3.599942)
			(size 0.3556 0.3556)
			(layers "F.Cu" "F.Mask" "F.Paste")
			(net "GND")
		)
		(pad "Y28" smd circle
			(at 9.99998 3.599942)
			(size 0.3556 0.3556)
			(layers "F.Cu" "F.Mask" "F.Paste")
			(net "IOC_SDA_2")
		)
		(pad "Y29" smd circle
			(at 10.80008 3.599942)
			(size 0.3556 0.3556)
			(layers "F.Cu" "F.Mask" "F.Paste")
			(net "SPARE4")
		)
		(pad "Y30" smd circle
			(at 11.599926 3.599942)
			(size 0.3556 0.3556)
			(layers "F.Cu" "F.Mask" "F.Paste")
			(net "IOC_GPIO_15")
		)
	)
)
